# BASEBOARD_FAB2 (Tioga Pass) — schematic netlist excerpt (pin names and nets, part order shuffled) for the footprints in the layout excerpt that follows; sources: Cadence DE-HDL packaged netlist, KiCad conversion of Wiwynn_Tioga_Pass_MB.brd

CT28  CAP  1000PF 50V 10% X7R  pkg 0402LF  page 224 : A = A_TSENSE_PVDDQ_GHJ ; B = GND
R2L19  RES  49.9K 1% CHIP  pkg 0402  page 237 : A = VR_P1V8_PCH_STBY_FB ; B = GND
R7C10  RES  20.0K 1% CHIP  pkg 0402  page 137 : A = P3V3_RTC_STBY ; B = RST_RTCRST_N

(kicad_pcb
	(version 20260206)
	(generator "pcbnew")
	(generator_version "10.0")
	(general
		(thickness 1.6)
		(legacy_teardrops no)
	)
	(paper "A4")
	(title_block
		(title "Wiwynn_Tioga_Pass_MB.brd")
		(comment 1 "Tioga Pass / footprints 3369-3371 of 4770")
	)
	(layers
		(0 "F.Cu" signal "TOP")
		(4 "In1.Cu" signal "L2GND")
		(6 "In2.Cu" signal "L3")
		(8 "In3.Cu" signal "L4GND")
		(10 "In4.Cu" signal "L5")
		(12 "In5.Cu" signal "L6GND")
		(14 "In6.Cu" signal "L7VCC")
		(16 "In7.Cu" signal "L8VCC")
		(18 "In8.Cu" signal "L9GND")
		(20 "In9.Cu" signal "L10")
		(22 "In10.Cu" signal "L11GND")
		(24 "In11.Cu" signal "L12")
		(26 "In12.Cu" signal "L13GND")
		(2 "B.Cu" signal "BOTTOM")
		(9 "F.Adhes" user "F.Adhesive")
		(11 "B.Adhes" user "B.Adhesive")
		(13 "F.Paste" user "Package Geometry/Pastemask Top")
		(15 "B.Paste" user "Package Geometry/Pastemask Bottom")
		(5 "F.SilkS" user "Ref Des/Silkscreen Top")
		(7 "B.SilkS" user "Ref Des/Silkscreen Bottom")
		(1 "F.Mask" user "Board Geometry/Soldermask Top")
		(3 "B.Mask" user "Board Geometry/Soldermask Bottom")
		(17 "Dwgs.User" user "User.Drawings")
		(19 "Cmts.User" user "User.Comments")
		(21 "Eco1.User" user "User.Eco1")
		(23 "Eco2.User" user "User.Eco2")
		(25 "Edge.Cuts" user "Board Geometry/Outline")
		(27 "Margin" user)
		(31 "F.CrtYd" user "Package Geometry/Place Bound Top")
		(29 "B.CrtYd" user "Package Geometry/Place Bound Bottom")
		(35 "F.Fab" user "Ref Des/Assembly Top")
		(33 "B.Fab" user "Ref Des/Assembly Bottom")
	)
	(footprint ""
		(layer "B.Cu")
		(at 1.9304 -8.4582)
		(property "Reference" "CT28"
			(at 0.8382 -0.84963 0)
			(unlocked yes)
			(layer "B.SilkS")
			(effects
				(font
					(size 0.7874 0.5842)
					(thickness 0.1524)
				)
				(justify left mirror)
			)
		)
		(property "Value" ""
			(at 0 0 0)
			(layer "B.Fab")
			(effects
				(font
					(size 1.27 1.27)
				)
				(justify mirror)
			)
		)
		(duplicate_pad_numbers_are_jumpers no)
		(fp_poly
			(pts
				(xy -0.3048 -0.1016) (xy -0.3048 0.9906) (xy 0.3048 0.9906) (xy 0.3048 -0.1016)
			)
			(stroke
				(width 0)
				(type default)
			)
			(fill no)
			(layer "B.CrtYd")
		)
		(fp_line
			(start -0.3048 -0.1016)
			(end 0.3048 -0.1016)
			(stroke
				(width 0.1)
				(type default)
			)
			(layer "B.Fab")
		)
		(fp_line
			(start -0.3048 0.9906)
			(end -0.3048 -0.1016)
			(stroke
				(width 0.1)
				(type default)
			)
			(layer "B.Fab")
		)
		(fp_line
			(start 0.3048 -0.1016)
			(end 0.3048 0.9906)
			(stroke
				(width 0.1)
				(type default)
			)
			(layer "B.Fab")
		)
		(fp_line
			(start 0.3048 0.9906)
			(end -0.3048 0.9906)
			(stroke
				(width 0.1)
				(type default)
			)
			(layer "B.Fab")
		)
		(pad "1" smd rect
			(at 0 0 180)
			(size 0.508 0.508)
			(layers "B.Cu" "B.Mask" "B.Paste")
			(net "A_TSENSE_PVDDQ_GHJ")
		)
		(pad "2" smd rect
			(at 0 0.889 180)
			(size 0.508 0.508)
			(layers "B.Cu" "B.Mask" "B.Paste")
			(net "GND")
		)
		(zone
			(layer "B.Cu")
			(hatch none 0.5)
			(connect_pads
				(clearance 0)
			)
			(min_thickness 0.25)
			(keepout
				(tracks allowed)
				(vias not_allowed)
				(pads allowed)
				(copperpour not_allowed)
				(footprints allowed)
			)
			(placement
				(enabled no)
				(sheetname "")
			)
			(fill
				(thermal_gap 0.5)
				(thermal_bridge_width 0.5)
				(island_removal_mode 0)
			)
			(polygon
				(pts
					(xy 2.1844 -8.2042) (xy 1.6764 -8.2042) (xy 1.6764 -7.8232) (xy 2.1844 -7.8232)
				)
			)
		)
		(zone
			(layer "B.Cu")
			(hatch none 0.5)
			(connect_pads
				(clearance 0)
			)
			(min_thickness 0.25)
			(keepout
				(tracks not_allowed)
				(vias allowed)
				(pads allowed)
				(copperpour not_allowed)
				(footprints allowed)
			)
			(placement
				(enabled no)
				(sheetname "")
			)
			(fill
				(thermal_gap 0.5)
				(thermal_bridge_width 0.5)
				(island_removal_mode 0)
			)
			(polygon
				(pts
					(xy 2.1844 -7.8232) (xy 1.6764 -7.8232) (xy 1.6764 -8.2042) (xy 2.1844 -8.2042)
				)
			)
		)
	)
	(footprint ""
		(layer "B.Cu")
		(at 402.463 -148.1074 180)
		(property "Reference" "R2L19"
			(at 0 0 0)
			(layer "B.SilkS")
			(hide yes)
			(effects
				(font
					(size 1.27 1.27)
				)
				(justify mirror)
			)
		)
		(property "Value" ""
			(at 0 0 0)
			(layer "B.Fab")
			(effects
				(font
					(size 1.27 1.27)
				)
				(justify mirror)
			)
		)
		(duplicate_pad_numbers_are_jumpers no)
		(fp_poly
			(pts
				(xy 0.2794 -0.1016) (xy -0.2794 -0.1016) (xy -0.2794 0.9906) (xy 0.2794 0.9906)
			)
			(stroke
				(width 0)
				(type default)
			)
			(fill no)
			(layer "B.CrtYd")
		)
		(fp_line
			(start 0.2794 0.9906)
			(end -0.2794 0.9906)
			(stroke
				(width 0.1)
				(type default)
			)
			(layer "B.Fab")
		)
		(fp_line
			(start 0.2794 -0.1016)
			(end 0.2794 0.9906)
			(stroke
				(width 0.1)
				(type default)
			)
			(layer "B.Fab")
		)
		(fp_line
			(start -0.2794 0.9906)
			(end -0.2794 -0.1016)
			(stroke
				(width 0.1)
				(type default)
			)
			(layer "B.Fab")
		)
		(fp_line
			(start -0.2794 -0.1016)
			(end 0.2794 -0.1016)
			(stroke
				(width 0.1)
				(type default)
			)
			(layer "B.Fab")
		)
		(pad "1" smd rect
			(at 0 0)
			(size 0.508 0.508)
			(layers "B.Cu" "B.Mask" "B.Paste")
			(net "VR_P1V8_PCH_STBY_FB")
		)
		(pad "2" smd rect
			(at 0 0.889)
			(size 0.508 0.508)
			(layers "B.Cu" "B.Mask" "B.Paste")
			(net "GND")
		)
		(zone
			(layer "B.Cu")
			(hatch none 0.5)
			(connect_pads
				(clearance 0)
			)
			(min_thickness 0.25)
			(keepout
				(tracks not_allowed)
				(vias allowed)
				(pads allowed)
				(copperpour not_allowed)
				(footprints allowed)
			)
			(placement
				(enabled no)
				(sheetname "")
			)
			(fill
				(thermal_gap 0.5)
				(thermal_bridge_width 0.5)
				(island_removal_mode 0)
			)
			(polygon
				(pts
					(xy 402.209 -148.7424) (xy 402.717 -148.7424) (xy 402.717 -148.3614) (xy 402.209 -148.3614)
				)
			)
		)
		(zone
			(layer "B.Cu")
			(hatch none 0.5)
			(connect_pads
				(clearance 0)
			)
			(min_thickness 0.25)
			(keepout
				(tracks allowed)
				(vias not_allowed)
				(pads allowed)
				(copperpour not_allowed)
				(footprints allowed)
			)
			(placement
				(enabled no)
				(sheetname "")
			)
			(fill
				(thermal_gap 0.5)
				(thermal_bridge_width 0.5)
				(island_removal_mode 0)
			)
			(polygon
				(pts
					(xy 402.209 -148.3614) (xy 402.717 -148.3614) (xy 402.717 -148.7424) (xy 402.209 -148.7424)
				)
			)
		)
	)
	(footprint ""
		(layer "B.Cu")
		(at 374.777 -90.2335 180)
		(property "Reference" "R7C10"
			(at 0 0 0)
			(layer "B.SilkS")
			(hide yes)
			(effects
				(font
					(size 1.27 1.27)
				)
				(justify mirror)
			)
		)
		(property "Value" ""
			(at 0 0 0)
			(layer "B.Fab")
			(effects
				(font
					(size 1.27 1.27)
				)
				(justify mirror)
			)
		)
		(duplicate_pad_numbers_are_jumpers no)
		(fp_poly
			(pts
				(xy 0.2794 -0.1016) (xy -0.2794 -0.1016) (xy -0.2794 0.9906) (xy 0.2794 0.9906)
			)
			(stroke
				(width 0)
				(type default)
			)
			(fill no)
			(layer "B.CrtYd")
		)
		(fp_line
			(start 0.2794 0.9906)
			(end -0.2794 0.9906)
			(stroke
				(width 0.1)
				(type default)
			)
			(layer "B.Fab")
		)
		(fp_line
			(start 0.2794 -0.1016)
			(end 0.2794 0.9906)
			(stroke
				(width 0.1)
				(type default)
			)
			(layer "B.Fab")
		)
		(fp_line
			(start -0.2794 0.9906)
			(end -0.2794 -0.1016)
			(stroke
				(width 0.1)
				(type default)
			)
			(layer "B.Fab")
		)
		(fp_line
			(start -0.2794 -0.1016)
			(end 0.2794 -0.1016)
			(stroke
				(width 0.1)
				(type default)
			)
			(layer "B.Fab")
		)
		(pad "1" smd rect
			(at 0 0)
			(size 0.508 0.508)
			(layers "B.Cu" "B.Mask" "B.Paste")
			(net "P3V3_RTC_STBY")
		)
		(pad "2" smd rect
			(at 0 0.889)
			(size 0.508 0.508)
			(layers "B.Cu" "B.Mask" "B.Paste")
			(net "RST_RTCRST_N")
		)
		(zone
			(layer "B.Cu")
			(hatch none 0.5)
			(connect_pads
				(clearance 0)
			)
			(min_thickness 0.25)
			(keepout
				(tracks not_allowed)
				(vias allowed)
				(pads allowed)
				(copperpour not_allowed)
				(footprints allowed)
			)
			(placement
				(enabled no)
				(sheetname "")
			)
			(fill
				(thermal_gap 0.5)
				(thermal_bridge_width 0.5)
				(island_removal_mode 0)
			)
			(polygon
				(pts
					(xy 374.523 -90.8685) (xy 375.031 -90.8685) (xy 375.031 -90.4875) (xy 374.523 -90.4875)
				)
			)
		)
		(zone
			(layer "B.Cu")
			(hatch none 0.5)
			(connect_pads
				(clearance 0)
			)
			(min_thickness 0.25)
			(keepout
				(tracks allowed)
				(vias not_allowed)
				(pads allowed)
				(copperpour not_allowed)
				(footprints allowed)
			)
			(placement
				(enabled no)
				(sheetname "")
			)
			(fill
				(thermal_gap 0.5)
				(thermal_bridge_width 0.5)
				(island_removal_mode 0)
			)
			(polygon
				(pts
					(xy 374.523 -90.4875) (xy 375.031 -90.4875) (xy 375.031 -90.8685) (xy 374.523 -90.8685)
				)
			)
		)
	)
)
